FILE_TYPE = CONNECTIVITY;
{Allegro Design Entry HDL 16.6-p007 (v16-6-112F) 10/10/2012}
"PAGE_NUMBER" = 152;
0"NC";
1"GND\g";
2"GND\g";
3"PVCCIO_CPU0\g";
4"GND\g";
5"GND\g";
6"P3V3\g";
7"PVCCIO_CPU0\g";
8"PVCCIO_CPU1\g";
9"PVCCIO_CPU0\g";
10"PVCCIO_CPU1\g";
11"H_CPU0_MEMABC_MEMHOT_LVT3_N";
12"H_CPU0_MEMABC_MEMHOT_G_PCH_N";
13"H_CPU0_MEMABC_MEMHOT_LVT3_K_N";
14"H_CPU0_MEMDEF_MEMHOT_G_PCH_N";
15"H_CPU0_ABC_MEMHOT_LVT3_R_N";
16"H_CPU0_MEMDEF_MEMHOT_LVT3_K_N";
17"P0V7_GTL2014_2"VOLTAGE"+0.7";
18"H_CPU0_MEMDEF_MEMHOT_LVT3_N";
19"H_CPU1_MEMGHJ_MEMHOT_LVT3_N";
20"H_CPU1_MEMKLM_MEMHOT_LVT3_N";
21"H_CPU1_MEMKLM_MEMHOT_LVT3_K_N";
22"H_CPU1_MEMKLM_MEMHOT_G_PCH_N";
23"H_CPU1_MEMGHJ_MEMHOT_LVT3_K_N";
24"H_CPU0_DEF_MEMHOT_LVT3_R_N";
25"H_CPU1_GHJ_MEMHOT_LVT3_R_N";
26"H_CPU1_MEMGHJ_MEMHOT_G_PCH_N";
27"H_CPU1_KLM_MEMHOT_LVT3_R_N";
28"PD_DIR_2";
29"P0V7_GTL2014_2";
30"H_CPU0_MEMABC_MEMHOT_G_R_N";
31"H_CPU0_MEMABC_MEMHOT_G_N";
32"H_CPU0_MEMDEF_MEMHOT_G_N";
33"H_CPU1_MEMGHJ_MEMHOT_G_R_N";
34"H_CPU0_MEMDEF_MEMHOT_G_R_N";
35"H_CPU1_MEMKLM_MEMHOT_G_R_N";
36"H_CPU1_MEMGHJ_MEMHOT_PCH_N";
37"H_CPU1_MEMGHJ_MEMHOT_LVT3_BMC_N";
38"H_CPU1_MEMKLM_MEMHOT_PCH_N";
39"H_CPU0_MEMABC_MEMHOT_LVT3_BMC_N";
40"H_CPU0_MEMDEF_MEMHOT_LVT3_BMC_N";
41"H_CPU1_MEMKLM_MEMHOT_LVT3_BMC_N";
42"H_CPU0_MEMABC_MEMHOT_PCH_N";
43"H_CPU0_MEMDEF_MEMHOT_PCH_N";
44"H_CPU0_MEMABC_MEMHOT_LVT3_N";
45"H_CPU1_MEMKLM_MEMHOT_G_N";
46"H_CPU1_MEMGHJ_MEMHOT_G_N";
47"H_CPU1_MEMGHJ_MEMHOT_LVT3_N";
48"H_CPU0_MEMDEF_MEMHOT_LVT3_N";
49"H_CPU1_MEMKLM_MEMHOT_LVT3_N";
%"GTL2014"
"1","(-5400,4050)","2","mstr_digital","I1";
;
CDS_SEC"1"
SEC"1"
BOM_COST"PROC_SIDEBAND"
SEC_TYPE"SM"
PACK_TYPE"SM"
ROOM"PROC_SIDEBAND"
CDS_LOCATION"U9G1"
CDS_LIB"mstr_digital"
LOCATION"U9G1"
MATERIAL"IC"
PART_NUMBER"D66151-001";
"A0"
$PN"13"27;
"A1"
$PN"12"25;
"A3"
$PN"9"15;
"A2"
$PN"10"24;
"B2"
$PN"5"34;
"B3"
$PN"6"30;
"B0"
$PN"2"35;
"B1"
$PN"3"33;
"GND<1>"
$PN"8"1;
"GND<2>"
$PN"11"1;
"GND<0>"
$PN"7"1;
"VCC"
$PN"14"6;
"VREF"
$PN"4"29;
"DIR"
$PN"1"28;
%"RES"
"1","(-6700,1400)","0","mstr_discrete","I100";
;
CDS_LOCATION"R3P63"
CDS_SEC"1"
$SEC"1"
CDS_LIB"mstr_discrete"
PACK_TYPE"0402"
MATERIAL"EMPTY"
PART_NUMBER"G21497-005"
LOCATION"R3P63"
TOLERANCE"5%"
VALUE"0.0"
WATTAGE"1/16W";
"B"
$PN"2"36;
"A"
$PN"1"47;
%"RES"
"1","(-6700,975)","0","mstr_discrete","I102";
;
CDS_LOCATION"R2U45"
CDS_SEC"1"
$SEC"1"
CDS_LIB"mstr_discrete"
LOCATION"R2U45"
PART_NUMBER"G21497-005"
PACK_TYPE"0402"
MATERIAL"EMPTY"
TOLERANCE"5%"
VALUE"0.0"
WATTAGE"1/16W";
"B"
$PN"2"38;
"A"
$PN"1"49;
%"RES"
"1","(-2450,4075)","0","mstr_discrete","I14";
;
CDS_SEC"1"
CDS_LOCATION"R9G31"
SEC"1"
BOM_COST"PROC_SIDEBAND"
SEC_TYPE"0402"
ROOM"PROC_SIDEBAND"
CDS_LIB"mstr_discrete"
LOCATION"R9G31"
MATERIAL"CHIP"
PACK_TYPE"0402"
PART_NUMBER"G21796-074"
WATTAGE"1/16W"
TOLERANCE"1%"
VALUE"33.2";
"B"
$PN"2"18;
"A"
$PN"1"16;
%"RES"
"1","(-2450,3900)","0","mstr_discrete","I15";
;
CDS_SEC"1"
SEC"1"
SEC_TYPE"0402"
BOM_COST"PROC_SIDEBAND"
ROOM"PROC_SIDEBAND"
CDS_LOCATION"R1U36"
CDS_LIB"mstr_discrete"
MATERIAL"CHIP"
PACK_TYPE"0402"
PART_NUMBER"G21796-074"
WATTAGE"1/16W"
LOCATION"R1U36"
TOLERANCE"1%"
VALUE"33.2";
"B"
$PN"2"19;
"A"
$PN"1"23;
%"RES"
"1","(-2450,3725)","0","mstr_discrete","I16";
;
CDS_SEC"1"
SEC"1"
BOM_COST"PROC_SIDEBAND"
SEC_TYPE"0402"
ROOM"PROC_TRANSLATORS"
CDS_LOCATION"R1U34"
CDS_LIB"mstr_discrete"
MATERIAL"CHIP"
PACK_TYPE"0402"
PART_NUMBER"G21796-074"
WATTAGE"1/16W"
LOCATION"R1U34"
TOLERANCE"1%"
VALUE"33.2";
"B"
$PN"2"20;
"A"
$PN"1"21;
%"GND"
"1","(-5900,3525)","0","mstr_symbols","I17";
;
HDL_POWER"GND"
VOLTAGE"0.0V"
CDS_LIB"mstr_symbols"
SIZE"1B"
BODY_TYPE"PLUMBING";
"A\NAC"1;
%"CAP"
"1","(-4525,4650)","0","mstr_discrete","I18";
;
CDS_SEC"1"
SEC_TYPE"0402"
BOM_COST"PROC_SIDEBAND"
SEC"1"
CDS_LIB"mstr_discrete"
CDS_LOCATION"C1U19"
ROOM"PROC_SIDEBAND"
VALUE"1.0UF"
LOCATION"C1U19"
VOLTAGE"16V"
TOLERANCE"10%"
PART_NUMBER"D97712-011"
PACK_TYPE"0402"
MATERIAL"X6S";
"A"
$PN"1"6;
"B"
$PN"2"2;
%"RES"
"1","(-4350,4200)","0","mstr_discrete","I2";
;
CDS_SEC"1"
CDS_LIB"mstr_discrete"
SEC"1"
SEC_TYPE"0402"
BOM_COST"PROC_SIDEBAND"
CDS_LOCATION"R1U30"
ROOM"PROC_TRANSLATORS"
PART_NUMBER"G21796-026"
MATERIAL"CHIP"
PACK_TYPE"0402"
WATTAGE"1/16W"
LOCATION"R1U30"
TOLERANCE"1%"
VALUE"1.00K";
"B"
$PN"2"5;
"A"
$PN"1"28;
%"GND"
"1","(-4525,4450)","0","mstr_symbols","I20";
;
HDL_POWER"GND"
SIZE"1B"
CDS_LIB"mstr_symbols"
VOLTAGE"0.0V"
BODY_TYPE"PLUMBING";
"A\NAC"2;
%"RES"
"2","(-1775,2000)","0","mstr_discrete","I25";
;
ROOM"PROC_SIDEBAND"
$SEC"1"
CDS_LOCATION"R1U43"
CDS_SEC"1"
BOM_COST"PROC_SIDEBAND"
CDS_LIB"mstr_discrete"
LOCATION"R1U43"
VALUE"49.9"
TOLERANCE"1%"
PART_NUMBER"G21796-047"
PACK_TYPE"0402"
MATERIAL"CHIP"
WATTAGE"1/16W";
"A"
$PN"1"3;
"B"
$PN"2"17;
%"RES"
"2","(-1775,1600)","0","mstr_discrete","I26";
;
BOM_COST"PROC_SIDEBAND"
CDS_SEC"1"
$SEC"1"
ROOM"PROC_SIDEBAND"
CDS_LOCATION"R1U37"
CDS_LIB"mstr_discrete"
PART_NUMBER"G21796-017"
WATTAGE"1/16W"
VALUE"100.0"
LOCATION"R1U37"
TOLERANCE"1%"
MATERIAL"CHIP"
PACK_TYPE"0402";
"A"
$PN"1"17;
"B"
$PN"2"4;
%"CAP_A"
"1","(-2150,1600)","0","dev_discrete","I27";
;
$SEC"1"
CDS_SEC"1"
BOM_COST"PROC_SIDEBAND"
ROOM"PROC_SIDEBAND"
CDS_LOCATION"C1U22"
CDS_LIB"dev_discrete"
LOCATION"C1U22"
PART_NUMBER"A36096-030"
VALUE"0.1UF"
TOLERANCE"10%"
PACK_TYPE"0402V"
VOLTAGE"16V"
MATERIAL"X7R";
"B"
$PN"2"4;
"A"
$PN"1"17;
%"PVCCIO_CPU0"
"1","(-1775,2350)","0","mstr_symbols","I28";
;
CDS_LIB"mstr_symbols"
HDL_POWER"PVCCIO_CPU0"
BODY_TYPE"PLUMBING"
VOLTAGE"1.1V";
"G\NAC"3;
%"GND"
"1","(-1775,1275)","0","mstr_symbols","I29";
;
HDL_POWER"GND"
CDS_LIB"mstr_symbols"
SIZE"1B"
BODY_TYPE"PLUMBING"
VOLTAGE"0.0V";
"A\NAC"4;
%"GND"
"1","(-3825,4125)","0","mstr_symbols","I3";
;
CDS_LIB"mstr_symbols"
HDL_POWER"GND"
VOLTAGE"0.0V"
SIZE"1B"
BODY_TYPE"PLUMBING";
"A\NAC"5;
%"RES"
"1","(-6950,4225)","0","mstr_discrete","I45";
;
CDS_SEC"1"
CDS_LOCATION"R9G34"
SEC_TYPE"0402"
SEC"1"
CDS_LIB"mstr_discrete"
TOLERANCE"5%"
PACK_TYPE"0402"
WATTAGE"1/16W"
MATERIAL"CHIP"
LOCATION"R9G34"
PART_NUMBER"G21497-005"
VALUE"0.0";
"B"
$PN"2"30;
"A"
$PN"1"31;
%"RES"
"2","(-3150,4600)","0","mstr_discrete","I47";
;
CDS_SEC"1"
CDS_LOCATION"R9G27"
SEC_TYPE"0402"
SEC"1"
CDS_LIB"mstr_discrete"
MATERIAL"EMPTY"
LOCATION"R9G27"
PART_NUMBER"G21497-005"
VALUE"0.0"
TOLERANCE"5%"
PACK_TYPE"0402"
WATTAGE"1/16W";
"A"
$PN"1"14;
"B"
$PN"2"16;
%"RES"
"1","(-6950,4050)","0","mstr_discrete","I49";
;
CDS_SEC"1"
CDS_LOCATION"R1U58"
SEC_TYPE"0402"
SEC"1"
PACK_TYPE"0402"
CDS_LIB"mstr_discrete"
TOLERANCE"5%"
WATTAGE"1/16W"
LOCATION"R1U58"
MATERIAL"CHIP"
PART_NUMBER"G21497-005"
VALUE"0.0";
"B"
$PN"2"34;
"A"
$PN"1"32;
%"P3V3"
"1","(-4775,4925)","0","mstr_symbols","I5";
;
VOLTAGE"3.3V"
CDS_LIB"mstr_symbols"
SIZE"1B"
BODY_TYPE"PLUMBING"
HDL_POWER"P3V3";
"G\NAC"6;
%"RES"
"2","(-7175,4525)","0","mstr_discrete","I50";
;
CDS_SEC"1"
CDS_LOCATION"R1U56"
SEC_TYPE"0402"
SEC"1"
CDS_LIB"mstr_discrete"
LOCATION"R1U56"
VALUE"0.0"
PART_NUMBER"G21497-005"
MATERIAL"EMPTY"
WATTAGE"1/16W"
TOLERANCE"5%"
PACK_TYPE"0402";
"A"
$PN"1"14;
"B"
$PN"2"32;
%"RES"
"2","(-7450,4525)","0","mstr_discrete","I51";
;
CDS_SEC"1"
CDS_LOCATION"R2U51"
SEC"1"
SEC_TYPE"0402"
CDS_LIB"mstr_discrete"
PART_NUMBER"G21497-005"
LOCATION"R2U51"
VALUE"0.0"
MATERIAL"EMPTY"
WATTAGE"1/16W"
TOLERANCE"5%"
PACK_TYPE"0402";
"A"
$PN"1"12;
"B"
$PN"2"31;
%"PVCCIO_CPU0"
"1","(-7925,4950)","0","mstr_symbols","I52";
;
CDS_LIB"mstr_symbols"
HDL_POWER"PVCCIO_CPU0"
VOLTAGE"1.1V"
BODY_TYPE"PLUMBING";
"G\NAC"7;
%"RES"
"2","(-7875,4650)","0","mstr_discrete","I53";
;
CDS_SEC"1"
SEC"1"
SEC_TYPE"0402"
CDS_LOCATION"R2U40"
CDS_LIB"mstr_discrete"
BOM_COST"PROC_SIDEBAND"
ROOM"PROC_SIDEBAND"
PART_NUMBER"G21796-009"
WATTAGE"1/16W"
TOLERANCE"1%"
LOCATION"R2U40"
VALUE"150.0"
PACK_TYPE"0402"
MATERIAL"CHIP";
"A"
$PN"1"7;
"B"
$PN"2"31;
%"RES"
"2","(-7975,4650)","2","mstr_discrete","I54";
;
CDS_SEC"1"
SEC"1"
SEC_TYPE"0402"
CDS_LOCATION"R2U41"
CDS_LIB"mstr_discrete"
BOM_COST"PROC_SIDEBAND"
ROOM"PROC_SIDEBAND"
TOLERANCE"1%"
LOCATION"R2U41"
VALUE"150.0"
WATTAGE"1/16W"
PACK_TYPE"0402"
MATERIAL"CHIP"
PART_NUMBER"G21796-009";
"A"
$PN"1"7;
"B"
$PN"2"32;
%"PVCCIO_CPU1"
"1","(-8375,4950)","0","mstr_symbols","I55";
;
VOLTAGE"1.1V"
CDS_LIB"mstr_symbols"
BODY_TYPE"PLUMBING"
HDL_POWER"PVCCIO_CPU1";
"G\NAC"8;
%"RES"
"2","(-8325,4650)","0","mstr_discrete","I56";
;
CDS_SEC"1"
SEC_TYPE"0402"
SEC"1"
CDS_LOCATION"R1U41"
CDS_LIB"mstr_discrete"
BOM_COST"PROC_SIDEBAND"
PART_NUMBER"G21796-009"
ROOM"PROC_SIDEBAND"
LOCATION"R1U41"
VALUE"150.0"
PACK_TYPE"0402"
MATERIAL"CHIP"
WATTAGE"1/16W"
TOLERANCE"1%";
"A"
$PN"1"8;
"B"
$PN"2"46;
%"RES"
"2","(-8425,4650)","2","mstr_discrete","I57";
;
CDS_SEC"1"
BOM_COST"PROC_SIDEBAND"
CDS_LIB"mstr_discrete"
SEC_TYPE"0402"
SEC"1"
CDS_LOCATION"R1U35"
ROOM"PROC_SIDEBAND"
LOCATION"R1U35"
VALUE"150.0"
TOLERANCE"1%"
WATTAGE"1/16W"
PACK_TYPE"0402"
MATERIAL"CHIP"
PART_NUMBER"G21796-009";
"A"
$PN"1"8;
"B"
$PN"2"45;
%"RES"
"2","(-7800,3250)","0","mstr_discrete","I58";
;
CDS_SEC"1"
SEC_TYPE"0402"
SEC"1"
CDS_LOCATION"R4P17"
CDS_LIB"mstr_discrete"
BOM_COST"PROC_SIDEBAND"
ROOM"PROC_SIDEBAND"
LOCATION"R4P17"
VALUE"150.0"
PACK_TYPE"0402"
MATERIAL"CHIP"
WATTAGE"1/16W"
PART_NUMBER"G21796-009"
TOLERANCE"1%";
"A"
$PN"1"31;
"B"
$PN"2"9;
%"RES"
"2","(-7900,3250)","2","mstr_discrete","I59";
;
CDS_SEC"1"
CDS_LOCATION"R4P20"
BOM_COST"PROC_SIDEBAND"
CDS_LIB"mstr_discrete"
PART_NUMBER"G21796-009"
SEC_TYPE"0402"
SEC"1"
ROOM"PROC_SIDEBAND"
LOCATION"R4P20"
VALUE"150.0"
TOLERANCE"1%"
WATTAGE"1/16W"
PACK_TYPE"0402"
MATERIAL"CHIP";
"A"
$PN"1"32;
"B"
$PN"2"9;
%"RES"
"1","(-2450,4250)","0","mstr_discrete","I6";
;
CDS_SEC"1"
SEC"1"
BOM_COST"PROC_SIDEBAND"
SEC_TYPE"0402"
ROOM"PROC_SIDEBAND"
CDS_LIB"mstr_discrete"
CDS_LOCATION"R1U46"
PACK_TYPE"0402"
MATERIAL"CHIP"
PART_NUMBER"G21796-074"
WATTAGE"1/16W"
TOLERANCE"1%"
LOCATION"R1U46"
VALUE"33.2";
"B"
$PN"2"11;
"A"
$PN"1"13;
%"PVCCIO_CPU0"
"1","(-7850,2925)","6","mstr_symbols","I60";
;
BODY_TYPE"PLUMBING"
VOLTAGE"1.1V"
CDS_LIB"mstr_symbols"
HDL_POWER"PVCCIO_CPU0";
"G\NAC"9;
%"RES"
"2","(-8250,3275)","0","mstr_discrete","I61";
;
CDS_SEC"1"
SEC_TYPE"0402"
SEC"1"
CDS_LOCATION"R7P5"
CDS_LIB"mstr_discrete"
BOM_COST"PROC_SIDEBAND"
ROOM"PROC_SIDEBAND"
LOCATION"R7P5"
VALUE"150.0"
TOLERANCE"1%"
PACK_TYPE"0402"
MATERIAL"CHIP"
WATTAGE"1/16W"
PART_NUMBER"G21796-009";
"A"
$PN"1"46;
"B"
$PN"2"10;
%"RES"
"2","(-8350,3275)","2","mstr_discrete","I62";
;
CDS_SEC"1"
SEC_TYPE"0402"
SEC"1"
CDS_LOCATION"R7P21"
CDS_LIB"mstr_discrete"
BOM_COST"PROC_SIDEBAND"
ROOM"PROC_SIDEBAND"
LOCATION"R7P21"
PART_NUMBER"G21796-009"
VALUE"150.0"
TOLERANCE"1%"
PACK_TYPE"0402"
MATERIAL"CHIP"
WATTAGE"1/16W";
"A"
$PN"1"45;
"B"
$PN"2"10;
%"PVCCIO_CPU1"
"1","(-8300,2925)","6","mstr_symbols","I63";
;
CDS_LIB"mstr_symbols"
HDL_POWER"PVCCIO_CPU1"
VOLTAGE"1.1V"
BODY_TYPE"PLUMBING";
"G\NAC"10;
%"RES"
"1","(-6950,3900)","0","mstr_discrete","I64";
;
CDS_SEC"1"
CDS_LOCATION"R1U53"
SEC_TYPE"0402"
SEC"1"
PACK_TYPE"0402"
CDS_LIB"mstr_discrete"
TOLERANCE"5%"
WATTAGE"1/16W"
MATERIAL"CHIP"
PART_NUMBER"G21497-005"
LOCATION"R1U53"
VALUE"0.0";
"B"
$PN"2"33;
"A"
$PN"1"46;
%"RES"
"1","(-6950,3750)","0","mstr_discrete","I65";
;
CDS_SEC"1"
CDS_LOCATION"R1U60"
PACK_TYPE"0402"
SEC"1"
SEC_TYPE"0402"
CDS_LIB"mstr_discrete"
WATTAGE"1/16W"
TOLERANCE"5%"
MATERIAL"CHIP"
LOCATION"R1U60"
PART_NUMBER"G21497-005"
VALUE"0.0";
"B"
$PN"2"35;
"A"
$PN"1"45;
%"RES"
"2","(-2850,4600)","0","mstr_discrete","I66";
;
CDS_SEC"1"
CDS_LOCATION"R2U49"
SEC_TYPE"0402"
SEC"1"
CDS_LIB"mstr_discrete"
PART_NUMBER"G21497-005"
LOCATION"R2U49"
VALUE"0.0"
TOLERANCE"5%"
MATERIAL"EMPTY"
WATTAGE"1/16W"
PACK_TYPE"0402";
"A"
$PN"1"12;
"B"
$PN"2"13;
%"RES"
"2","(-7175,3500)","0","mstr_discrete","I67";
;
CDS_SEC"1"
CDS_LOCATION"R1U55"
SEC"1"
SEC_TYPE"0402"
CDS_LIB"mstr_discrete"
LOCATION"R1U55"
VALUE"0.0"
PART_NUMBER"G21497-005"
MATERIAL"EMPTY"
WATTAGE"1/16W"
TOLERANCE"5%"
PACK_TYPE"0402";
"A"
$PN"1"46;
"B"
$PN"2"26;
%"RES"
"2","(-7450,3500)","0","mstr_discrete","I68";
;
CDS_SEC"1"
CDS_LOCATION"R1U62"
SEC_TYPE"0402"
SEC"1"
CDS_LIB"mstr_discrete"
PART_NUMBER"G21497-005"
LOCATION"R1U62"
VALUE"0.0"
MATERIAL"EMPTY"
WATTAGE"1/16W"
TOLERANCE"5%"
PACK_TYPE"0402";
"A"
$PN"1"45;
"B"
$PN"2"22;
%"RES"
"2","(-3175,3425)","0","mstr_discrete","I69";
;
CDS_SEC"1"
CDS_LOCATION"R1U57"
SEC"1"
SEC_TYPE"0402"
CDS_LIB"mstr_discrete"
MATERIAL"EMPTY"
LOCATION"R1U57"
PART_NUMBER"G21497-005"
VALUE"0.0"
TOLERANCE"5%"
PACK_TYPE"0402"
WATTAGE"1/16W";
"A"
$PN"1"23;
"B"
$PN"2"26;
%"RES"
"2","(-2875,3425)","0","mstr_discrete","I70";
;
CDS_SEC"1"
CDS_LOCATION"R1U61"
SEC_TYPE"0402"
SEC"1"
CDS_LIB"mstr_discrete"
PART_NUMBER"G21497-005"
MATERIAL"EMPTY"
LOCATION"R1U61"
VALUE"0.0"
TOLERANCE"5%"
PACK_TYPE"0402"
WATTAGE"1/16W";
"A"
$PN"1"21;
"B"
$PN"2"22;
%"RES"
"1","(-3375,3725)","0","mstr_discrete","I71";
;
CDS_SEC"1"
CDS_LOCATION"R9G28"
SEC_TYPE"0402"
SEC"1"
CDS_LIB"mstr_discrete"
TOLERANCE"5%"
PACK_TYPE"0402"
WATTAGE"1/16W"
LOCATION"R9G28"
PART_NUMBER"G21497-005"
MATERIAL"CHIP"
VALUE"0.0";
"B"
$PN"2"21;
"A"
$PN"1"27;
%"RES"
"1","(-3375,3900)","0","mstr_discrete","I72";
;
CDS_SEC"1"
CDS_LOCATION"R9G32"
SEC"1"
SEC_TYPE"0402"
PACK_TYPE"0402"
CDS_LIB"mstr_discrete"
WATTAGE"1/16W"
TOLERANCE"5%"
LOCATION"R9G32"
PART_NUMBER"G21497-005"
MATERIAL"CHIP"
VALUE"0.0";
"B"
$PN"2"23;
"A"
$PN"1"25;
%"RES"
"1","(-3375,4075)","0","mstr_discrete","I73";
;
CDS_SEC"1"
CDS_LOCATION"R9G33"
SEC"1"
SEC_TYPE"0402"
CDS_LIB"mstr_discrete"
PACK_TYPE"0402"
TOLERANCE"5%"
WATTAGE"1/16W"
LOCATION"R9G33"
VALUE"0.0"
PART_NUMBER"G21497-005"
MATERIAL"CHIP";
"B"
$PN"2"16;
"A"
$PN"1"24;
%"RES"
"1","(-3375,4250)","0","mstr_discrete","I74";
;
CDS_SEC"1"
CDS_LOCATION"R1U59"
PACK_TYPE"0402"
SEC"1"
SEC_TYPE"0402"
CDS_LIB"mstr_discrete"
WATTAGE"1/16W"
TOLERANCE"5%"
LOCATION"R1U59"
PART_NUMBER"G21497-005"
MATERIAL"CHIP"
VALUE"0.0";
"B"
$PN"2"13;
"A"
$PN"1"15;
%"RES"
"1","(-6700,2475)","0","mstr_discrete","I79";
;
CDS_SEC"1"
CDS_LOCATION"R2U47"
SEC_TYPE"0402"
SEC"1"
CDS_LIB"mstr_discrete"
PACK_TYPE"0402"
LOCATION"R2U47"
PART_NUMBER"G21497-005"
MATERIAL"CHIP"
TOLERANCE"5%"
VALUE"0.0"
WATTAGE"1/16W";
"B"
$PN"2"39;
"A"
$PN"1"44;
%"RES"
"1","(-6700,2025)","0","mstr_discrete","I92";
;
CDS_SEC"1"
CDS_LOCATION"R9G29"
SEC_TYPE"0402"
SEC"1"
CDS_LIB"mstr_discrete"
PART_NUMBER"G21497-005"
LOCATION"R9G29"
VALUE"0.0"
PACK_TYPE"0402"
MATERIAL"CHIP"
TOLERANCE"5%"
WATTAGE"1/16W";
"B"
$PN"2"40;
"A"
$PN"1"48;
%"RES"
"1","(-6700,1600)","0","mstr_discrete","I93";
;
CDS_SEC"1"
CDS_LOCATION"R1U54"
SEC_TYPE"0402"
SEC"1"
CDS_LIB"mstr_discrete"
PACK_TYPE"0402"
LOCATION"R1U54"
PART_NUMBER"G21497-005"
MATERIAL"CHIP"
TOLERANCE"5%"
VALUE"0.0"
WATTAGE"1/16W";
"B"
$PN"2"37;
"A"
$PN"1"47;
%"RES"
"1","(-6700,1175)","0","mstr_discrete","I94";
;
CDS_SEC"1"
CDS_LOCATION"R2U46"
SEC_TYPE"0402"
SEC"1"
CDS_LIB"mstr_discrete"
PACK_TYPE"0402"
LOCATION"R2U46"
PART_NUMBER"G21497-005"
MATERIAL"CHIP"
TOLERANCE"5%"
VALUE"0.0"
WATTAGE"1/16W";
"B"
$PN"2"41;
"A"
$PN"1"49;
%"RES"
"1","(-6700,2275)","0","mstr_discrete","I95";
;
CDS_LOCATION"R3N30"
CDS_SEC"1"
$SEC"1"
CDS_LIB"mstr_discrete"
PACK_TYPE"0402"
MATERIAL"EMPTY"
LOCATION"R3N30"
PART_NUMBER"G21497-005"
TOLERANCE"5%"
VALUE"0.0"
WATTAGE"1/16W";
"B"
$PN"2"42;
"A"
$PN"1"44;
%"RES"
"1","(-6700,1825)","0","mstr_discrete","I98";
;
CDS_LOCATION"R9G30"
CDS_SEC"1"
$SEC"1"
CDS_LIB"mstr_discrete"
PACK_TYPE"0402"
MATERIAL"EMPTY"
PART_NUMBER"G21497-005"
LOCATION"R9G30"
VALUE"0.0"
TOLERANCE"5%"
WATTAGE"1/16W";
"B"
$PN"2"43;
"A"
$PN"1"48;
END.
